(kicad_pcb
	(version 20260206)
	(generator "pcbnew")
	(generator_version "10.0")
	(general
		(thickness 1.6)
		(legacy_teardrops no)
	)
	(paper "A4")
	(title_block
		(title "pdpb — Lightning_PDPB_BRD.brd")
		(comment 1 "Lightning (Wiwynn / Facebook NVMe JBOF) / footprints 621-627 of 1140")
	)
	(layers
		(0 "F.Cu" signal "TOP")
		(4 "In1.Cu" signal "L2GND")
		(6 "In2.Cu" signal "L3")
		(8 "In3.Cu" signal "L4VCC")
		(10 "In4.Cu" signal "L5VCC")
		(12 "In5.Cu" signal "L6")
		(14 "In6.Cu" signal "L7GND")
		(2 "B.Cu" signal "BOTTOM")
		(9 "F.Adhes" user "F.Adhesive")
		(11 "B.Adhes" user "B.Adhesive")
		(13 "F.Paste" user "Package Geometry/Pastemask Top")
		(15 "B.Paste" user "Package Geometry/Pastemask Bottom")
		(5 "F.SilkS" user "Ref Des/Silkscreen Top")
		(7 "B.SilkS" user "Ref Des/Silkscreen Bottom")
		(1 "F.Mask" user "Board Geometry/Soldermask Top")
		(3 "B.Mask" user "Board Geometry/Soldermask Bottom")
		(17 "Dwgs.User" user "User.Drawings")
		(19 "Cmts.User" user "User.Comments")
		(21 "Eco1.User" user "User.Eco1")
		(23 "Eco2.User" user "User.Eco2")
		(25 "Edge.Cuts" user "Board Geometry/Outline")
		(27 "Margin" user)
		(31 "F.CrtYd" user "Package Geometry/Place Bound Top")
		(29 "B.CrtYd" user "Package Geometry/Place Bound Bottom")
		(35 "F.Fab" user "Ref Des/Assembly Top")
		(33 "B.Fab" user "Ref Des/Assembly Bottom")
	)
	(footprint ""
		(layer "F.Cu")
		(at 213.3981 -197.5231 180)
		(property "Reference" "R9800"
			(at 0 0 180)
			(layer "F.SilkS")
			(hide yes)
			(effects
				(font
					(size 1.27 1.27)
				)
			)
		)
		(property "Value" "47KR2J-2-GP"
			(at 0.064008 -3.993896 180)
			(unlocked yes)
			(layer "F.Fab")
			(hide yes)
			(effects
				(font
					(size 1.016 1.016)
					(thickness 0.1524)
				)
			)
		)
		(property "Device Type" "R402H16"
			(at 0.064008 -5.517896 180)
			(unlocked yes)
			(layer "F.Fab")
			(hide yes)
			(effects
				(font
					(size 1.016 1.016)
					(thickness 0.1524)
				)
			)
		)
		(duplicate_pad_numbers_are_jumpers no)
		(fp_line
			(start 0.508 -0.9398)
			(end -0.508 -0.9398)
			(stroke
				(width 0.1524)
				(type default)
			)
			(layer "F.SilkS")
		)
		(fp_line
			(start -0.508 -0.9398)
			(end -0.508 0.9398)
			(stroke
				(width 0.1524)
				(type default)
			)
			(layer "F.SilkS")
		)
		(fp_rect
			(start -0.508 0.9398)
			(end 0.508 -0.9398)
			(stroke
				(width 0)
				(type default)
			)
			(fill no)
			(layer "F.CrtYd")
		)
		(fp_rect
			(start -0.508 0.9398)
			(end 0.508 -0.9398)
			(stroke
				(width 0)
				(type default)
			)
			(fill no)
			(layer "F.Fab")
		)
		(pad "1" smd custom
			(at 0 -0.4445 180)
			(size 0.1397 0.1397)
			(layers "F.Cu" "F.Mask" "F.Paste")
			(net "P12V")
			(options
				(clearance outline)
				(anchor circle)
			)
			(primitives
				(gr_poly
					(pts
						(arc
							(start -0.1778 -0.2794)
							(mid -0.249642 -0.249642)
							(end -0.2794 -0.1778)
						)
						(arc
							(start -0.2794 0.1778)
							(mid -0.249642 0.249642)
							(end -0.1778 0.2794)
						)
						(arc
							(start 0.1778 0.2794)
							(mid 0.249642 0.249642)
							(end 0.2794 0.1778)
						)
						(arc
							(start 0.2794 -0.1778)
							(mid 0.249642 -0.249642)
							(end 0.1778 -0.2794)
						)
					)
					(width 0)
					(fill yes)
				)
			)
		)
		(pad "2" smd custom
			(at 0 0.4445 180)
			(size 0.1397 0.1397)
			(layers "F.Cu" "F.Mask" "F.Paste")
			(net "P12V_MOST3_GATE")
			(options
				(clearance outline)
				(anchor circle)
			)
			(primitives
				(gr_poly
					(pts
						(arc
							(start -0.1778 -0.2794)
							(mid -0.249642 -0.249642)
							(end -0.2794 -0.1778)
						)
						(arc
							(start -0.2794 0.1778)
							(mid -0.249642 0.249642)
							(end -0.1778 0.2794)
						)
						(arc
							(start 0.1778 0.2794)
							(mid 0.249642 0.249642)
							(end 0.2794 0.1778)
						)
						(arc
							(start 0.2794 -0.1778)
							(mid 0.249642 -0.249642)
							(end 0.1778 -0.2794)
						)
					)
					(width 0)
					(fill yes)
				)
			)
		)
	)
	(footprint ""
		(layer "F.Cu")
		(at 219.964 -297.434 180)
		(property "Reference" "PC1190"
			(at 0 0 180)
			(layer "F.SilkS")
			(hide yes)
			(effects
				(font
					(size 1.27 1.27)
				)
			)
		)
		(property "Value" "SC22U25V6KX-GP-U"
			(at -2.860802 -5.279644 180)
			(unlocked yes)
			(layer "F.Fab")
			(hide yes)
			(effects
				(font
					(size 1.016 1.016)
					(thickness 0.1524)
				)
			)
		)
		(property "Device Type" "C1206-TO0D3H75"
			(at -2.860802 -6.803644 180)
			(unlocked yes)
			(layer "F.Fab")
			(hide yes)
			(effects
				(font
					(size 1.016 1.016)
					(thickness 0.1524)
				)
			)
		)
		(duplicate_pad_numbers_are_jumpers no)
		(fp_line
			(start 1.3081 2.3749)
			(end -1.3081 2.3749)
			(stroke
				(width 0.1524)
				(type default)
			)
			(layer "F.SilkS")
		)
		(fp_line
			(start 1.3081 -2.3749)
			(end 1.3081 2.3749)
			(stroke
				(width 0.1524)
				(type default)
			)
			(layer "F.SilkS")
		)
		(fp_line
			(start -1.3081 2.3749)
			(end -1.3081 -2.3749)
			(stroke
				(width 0.1524)
				(type default)
			)
			(layer "F.SilkS")
		)
		(fp_line
			(start -1.3081 -2.3749)
			(end 1.3081 -2.3749)
			(stroke
				(width 0.1524)
				(type default)
			)
			(layer "F.SilkS")
		)
		(fp_rect
			(start -0.8001 1.6002)
			(end 0.8001 -1.6002)
			(stroke
				(width 0)
				(type default)
			)
			(fill no)
			(layer "F.CrtYd")
		)
		(fp_poly
			(pts
				(xy -1.5621 2.4511) (xy -1.5621 1.6002) (xy 0.8001 1.6002) (xy 0.8001 -1.6002) (xy -0.8001 -1.6002)
				(xy -0.8001 1.5875) (xy -1.5621 1.5875) (xy -1.5621 -2.4511) (xy 1.5621 -2.4511) (xy 1.5621 2.4511)
			)
			(stroke
				(width 0)
				(type default)
			)
			(fill no)
			(layer "F.CrtYd")
		)
		(fp_rect
			(start -1.5621 2.4511)
			(end 1.5621 -2.4511)
			(stroke
				(width 0)
				(type default)
			)
			(fill no)
			(layer "F.Fab")
		)
		(pad "1" smd rect
			(at 0 -1.392936 180)
			(size 2.1082 1.4478)
			(layers "F.Cu" "F.Mask" "F.Paste")
			(net "P12V_SSD2")
		)
		(pad "2" smd rect
			(at 0 1.392936 180)
			(size 2.1082 1.4478)
			(layers "F.Cu" "F.Mask" "F.Paste")
			(net "GND")
		)
	)
	(footprint ""
		(layer "F.Cu")
		(at 24.003 -53.34 -90)
		(property "Reference" "R9456"
			(at 0 0 270)
			(layer "F.SilkS")
			(hide yes)
			(effects
				(font
					(size 1.27 1.27)
				)
			)
		)
		(property "Value" "330R2F-GP"
			(at 0.064008 -3.993896 270)
			(unlocked yes)
			(layer "F.Fab")
			(hide yes)
			(effects
				(font
					(size 1.016 1.016)
					(thickness 0.1524)
				)
			)
		)
		(property "Device Type" "R402H16"
			(at 0.064008 -5.517896 270)
			(unlocked yes)
			(layer "F.Fab")
			(hide yes)
			(effects
				(font
					(size 1.016 1.016)
					(thickness 0.1524)
				)
			)
		)
		(duplicate_pad_numbers_are_jumpers no)
		(fp_line
			(start -0.508 -0.9398)
			(end -0.508 0.9398)
			(stroke
				(width 0.1524)
				(type default)
			)
			(layer "F.SilkS")
		)
		(fp_line
			(start 0.508 -0.9398)
			(end -0.508 -0.9398)
			(stroke
				(width 0.1524)
				(type default)
			)
			(layer "F.SilkS")
		)
		(fp_rect
			(start -0.508 0.9398)
			(end 0.508 -0.9398)
			(stroke
				(width 0)
				(type default)
			)
			(fill no)
			(layer "F.CrtYd")
		)
		(fp_rect
			(start -0.508 0.9398)
			(end 0.508 -0.9398)
			(stroke
				(width 0)
				(type default)
			)
			(fill no)
			(layer "F.Fab")
		)
		(pad "1" smd custom
			(at 0 -0.4445 270)
			(size 0.1397 0.1397)
			(layers "F.Cu" "F.Mask" "F.Paste")
			(net "P3V3")
			(options
				(clearance outline)
				(anchor circle)
			)
			(primitives
				(gr_poly
					(pts
						(arc
							(start -0.1778 -0.2794)
							(mid -0.249642 -0.249642)
							(end -0.2794 -0.1778)
						)
						(arc
							(start -0.2794 0.1778)
							(mid -0.249642 0.249642)
							(end -0.1778 0.2794)
						)
						(arc
							(start 0.1778 0.2794)
							(mid 0.249642 0.249642)
							(end 0.2794 0.1778)
						)
						(arc
							(start 0.2794 -0.1778)
							(mid 0.249642 -0.249642)
							(end 0.1778 -0.2794)
						)
					)
					(width 0)
					(fill yes)
				)
			)
		)
		(pad "2" smd custom
			(at 0 0.4445 270)
			(size 0.1397 0.1397)
			(layers "F.Cu" "F.Mask" "F.Paste")
			(net "DRV_ATTN_14")
			(options
				(clearance outline)
				(anchor circle)
			)
			(primitives
				(gr_poly
					(pts
						(arc
							(start -0.1778 -0.2794)
							(mid -0.249642 -0.249642)
							(end -0.2794 -0.1778)
						)
						(arc
							(start -0.2794 0.1778)
							(mid -0.249642 0.249642)
							(end -0.1778 0.2794)
						)
						(arc
							(start 0.1778 0.2794)
							(mid 0.249642 0.249642)
							(end 0.2794 0.1778)
						)
						(arc
							(start 0.2794 -0.1778)
							(mid 0.249642 -0.249642)
							(end 0.1778 -0.2794)
						)
					)
					(width 0)
					(fill yes)
				)
			)
		)
	)
	(footprint ""
		(layer "F.Cu")
		(at 102.616 -205.486 90)
		(property "Reference" "R9085"
			(at 0 0 90)
			(layer "F.SilkS")
			(hide yes)
			(effects
				(font
					(size 1.27 1.27)
				)
			)
		)
		(property "Value" "27R2F-GP"
			(at 0.064008 -3.993896 90)
			(unlocked yes)
			(layer "F.Fab")
			(hide yes)
			(effects
				(font
					(size 1.016 1.016)
					(thickness 0.1524)
				)
			)
		)
		(property "Device Type" "R402H16"
			(at 0.064008 -5.517896 90)
			(unlocked yes)
			(layer "F.Fab")
			(hide yes)
			(effects
				(font
					(size 1.016 1.016)
					(thickness 0.1524)
				)
			)
		)
		(duplicate_pad_numbers_are_jumpers no)
		(fp_line
			(start 0.508 -0.9398)
			(end -0.508 -0.9398)
			(stroke
				(width 0.1524)
				(type default)
			)
			(layer "F.SilkS")
		)
		(fp_line
			(start -0.508 -0.9398)
			(end -0.508 0.9398)
			(stroke
				(width 0.1524)
				(type default)
			)
			(layer "F.SilkS")
		)
		(fp_rect
			(start -0.508 0.9398)
			(end 0.508 -0.9398)
			(stroke
				(width 0)
				(type default)
			)
			(fill no)
			(layer "F.CrtYd")
		)
		(fp_rect
			(start -0.508 0.9398)
			(end 0.508 -0.9398)
			(stroke
				(width 0)
				(type default)
			)
			(fill no)
			(layer "F.Fab")
		)
		(pad "1" smd custom
			(at 0 -0.4445 90)
			(size 0.1397 0.1397)
			(layers "F.Cu" "F.Mask" "F.Paste")
			(net "PE_CLK_100M_DR3_2_R_N")
			(options
				(clearance outline)
				(anchor circle)
			)
			(primitives
				(gr_poly
					(pts
						(arc
							(start -0.1778 -0.2794)
							(mid -0.249642 -0.249642)
							(end -0.2794 -0.1778)
						)
						(arc
							(start -0.2794 0.1778)
							(mid -0.249642 0.249642)
							(end -0.1778 0.2794)
						)
						(arc
							(start 0.1778 0.2794)
							(mid 0.249642 0.249642)
							(end 0.2794 0.1778)
						)
						(arc
							(start 0.2794 -0.1778)
							(mid 0.249642 -0.249642)
							(end 0.1778 -0.2794)
						)
					)
					(width 0)
					(fill yes)
				)
			)
		)
		(pad "2" smd custom
			(at 0 0.4445 90)
			(size 0.1397 0.1397)
			(layers "F.Cu" "F.Mask" "F.Paste")
			(net "PE_CLK100M_DR3_2_N")
			(options
				(clearance outline)
				(anchor circle)
			)
			(primitives
				(gr_poly
					(pts
						(arc
							(start -0.1778 -0.2794)
							(mid -0.249642 -0.249642)
							(end -0.2794 -0.1778)
						)
						(arc
							(start -0.2794 0.1778)
							(mid -0.249642 0.249642)
							(end -0.1778 0.2794)
						)
						(arc
							(start 0.1778 0.2794)
							(mid 0.249642 0.249642)
							(end 0.2794 0.1778)
						)
						(arc
							(start 0.2794 -0.1778)
							(mid 0.249642 -0.249642)
							(end 0.1778 -0.2794)
						)
					)
					(width 0)
					(fill yes)
				)
			)
		)
	)
	(footprint ""
		(layer "F.Cu")
		(at 24.3078 -190.119 180)
		(property "Reference" "R574"
			(at 0 0 180)
			(layer "F.SilkS")
			(hide yes)
			(effects
				(font
					(size 1.27 1.27)
				)
			)
		)
		(property "Value" "300KR2F-GP"
			(at 0.064008 -3.993896 180)
			(unlocked yes)
			(layer "F.Fab")
			(hide yes)
			(effects
				(font
					(size 1.016 1.016)
					(thickness 0.1524)
				)
			)
		)
		(property "Device Type" "R402H16"
			(at 0.064008 -5.517896 180)
			(unlocked yes)
			(layer "F.Fab")
			(hide yes)
			(effects
				(font
					(size 1.016 1.016)
					(thickness 0.1524)
				)
			)
		)
		(duplicate_pad_numbers_are_jumpers no)
		(fp_line
			(start 0.508 -0.9398)
			(end -0.508 -0.9398)
			(stroke
				(width 0.1524)
				(type default)
			)
			(layer "F.SilkS")
		)
		(fp_line
			(start -0.508 -0.9398)
			(end -0.508 0.9398)
			(stroke
				(width 0.1524)
				(type default)
			)
			(layer "F.SilkS")
		)
		(fp_rect
			(start -0.508 0.9398)
			(end 0.508 -0.9398)
			(stroke
				(width 0)
				(type default)
			)
			(fill no)
			(layer "F.CrtYd")
		)
		(fp_rect
			(start -0.508 0.9398)
			(end 0.508 -0.9398)
			(stroke
				(width 0)
				(type default)
			)
			(fill no)
			(layer "F.Fab")
		)
		(pad "1" smd custom
			(at 0 -0.4445 180)
			(size 0.1397 0.1397)
			(layers "F.Cu" "F.Mask" "F.Paste")
			(net "SW_SSD8_N")
			(options
				(clearance outline)
				(anchor circle)
			)
			(primitives
				(gr_poly
					(pts
						(arc
							(start -0.1778 -0.2794)
							(mid -0.249642 -0.249642)
							(end -0.2794 -0.1778)
						)
						(arc
							(start -0.2794 0.1778)
							(mid -0.249642 0.249642)
							(end -0.1778 0.2794)
						)
						(arc
							(start 0.1778 0.2794)
							(mid 0.249642 0.249642)
							(end 0.2794 0.1778)
						)
						(arc
							(start 0.2794 -0.1778)
							(mid 0.249642 -0.249642)
							(end 0.1778 -0.2794)
						)
					)
					(width 0)
					(fill yes)
				)
			)
		)
		(pad "2" smd custom
			(at 0 0.4445 180)
			(size 0.1397 0.1397)
			(layers "F.Cu" "F.Mask" "F.Paste")
			(net "P12V")
			(options
				(clearance outline)
				(anchor circle)
			)
			(primitives
				(gr_poly
					(pts
						(arc
							(start -0.1778 -0.2794)
							(mid -0.249642 -0.249642)
							(end -0.2794 -0.1778)
						)
						(arc
							(start -0.2794 0.1778)
							(mid -0.249642 0.249642)
							(end -0.1778 0.2794)
						)
						(arc
							(start 0.1778 0.2794)
							(mid 0.249642 0.249642)
							(end 0.2794 0.1778)
						)
						(arc
							(start 0.2794 -0.1778)
							(mid 0.249642 -0.249642)
							(end 0.1778 -0.2794)
						)
					)
					(width 0)
					(fill yes)
				)
			)
		)
	)
	(footprint ""
		(layer "F.Cu")
		(at 19.547332 -365.002826 90)
		(property "Reference" "Q85"
			(at 0 0 90)
			(layer "F.SilkS")
			(hide yes)
			(effects
				(font
					(size 1.27 1.27)
				)
			)
		)
		(property "Value" "2N7002A-7-GP"
			(at 0.127 -8.9662 90)
			(unlocked yes)
			(layer "F.Fab")
			(hide yes)
			(effects
				(font
					(size 1.016 1.016)
					(thickness 0.1524)
				)
			)
		)
		(property "Device Type" "SOT23DGS2D4H48"
			(at 0.127 -10.4902 90)
			(unlocked yes)
			(layer "F.Fab")
			(hide yes)
			(effects
				(font
					(size 1.016 1.016)
					(thickness 0.1524)
				)
			)
		)
		(duplicate_pad_numbers_are_jumpers no)
		(fp_line
			(start 1.651 -1.778)
			(end -1.651 -1.778)
			(stroke
				(width 0.1524)
				(type default)
			)
			(layer "F.SilkS")
		)
		(fp_line
			(start -1.651 -1.778)
			(end -1.651 1.778)
			(stroke
				(width 0.1524)
				(type default)
			)
			(layer "F.SilkS")
		)
		(fp_line
			(start 1.651 1.778)
			(end 1.651 -1.778)
			(stroke
				(width 0.1524)
				(type default)
			)
			(layer "F.SilkS")
		)
		(fp_line
			(start -1.651 1.778)
			(end 1.651 1.778)
			(stroke
				(width 0.1524)
				(type default)
			)
			(layer "F.SilkS")
		)
		(fp_poly
			(pts
				(xy -1.778 1.8796) (xy -1.778 -1.8796) (xy 1.778 -1.8796) (xy 1.778 1.8796)
			)
			(stroke
				(width 0)
				(type default)
			)
			(fill no)
			(layer "F.CrtYd")
		)
		(fp_poly
			(pts
				(xy -1.778 1.8796) (xy -1.778 -1.8796) (xy 1.778 -1.8796) (xy 1.778 1.8796)
			)
			(stroke
				(width 0)
				(type default)
			)
			(fill no)
			(layer "F.Fab")
		)
		(pad "D" smd custom
			(at 0 -0.9525 90)
			(size 0.1905 0.1905)
			(layers "F.Cu" "F.Mask" "F.Paste")
			(net "ATTN_LED_DR11_MOS_N")
			(options
				(clearance outline)
				(anchor circle)
			)
			(primitives
				(gr_poly
					(pts
						(arc
							(start -0.1778 0.5715)
							(mid -0.321484 0.511984)
							(end -0.381 0.3683)
						)
						(arc
							(start -0.381 -0.3683)
							(mid -0.321484 -0.511984)
							(end -0.1778 -0.5715)
						)
						(arc
							(start 0.1778 -0.5715)
							(mid 0.321484 -0.511984)
							(end 0.381 -0.3683)
						)
						(arc
							(start 0.381 0.3683)
							(mid 0.321484 0.511984)
							(end 0.1778 0.5715)
						)
					)
					(width 0)
					(fill yes)
				)
			)
		)
		(pad "G" smd custom
			(at -0.98425 0.9525 90)
			(size 0.1905 0.1905)
			(layers "F.Cu" "F.Mask" "F.Paste")
			(net "SSD11_CLK0_OE_MOS_N")
			(options
				(clearance outline)
				(anchor circle)
			)
			(primitives
				(gr_poly
					(pts
						(arc
							(start -0.1778 0.5715)
							(mid -0.321484 0.511984)
							(end -0.381 0.3683)
						)
						(arc
							(start -0.381 -0.3683)
							(mid -0.321484 -0.511984)
							(end -0.1778 -0.5715)
						)
						(arc
							(start 0.1778 -0.5715)
							(mid 0.321484 -0.511984)
							(end 0.381 -0.3683)
						)
						(arc
							(start 0.381 0.3683)
							(mid 0.321484 0.511984)
							(end 0.1778 0.5715)
						)
					)
					(width 0)
					(fill yes)
				)
			)
		)
		(pad "S" smd custom
			(at 0.98425 0.9525 90)
			(size 0.1905 0.1905)
			(layers "F.Cu" "F.Mask" "F.Paste")
			(net "ATTN_LED_DR11_R")
			(options
				(clearance outline)
				(anchor circle)
			)
			(primitives
				(gr_poly
					(pts
						(arc
							(start -0.1778 0.5715)
							(mid -0.321484 0.511984)
							(end -0.381 0.3683)
						)
						(arc
							(start -0.381 -0.3683)
							(mid -0.321484 -0.511984)
							(end -0.1778 -0.5715)
						)
						(arc
							(start 0.1778 -0.5715)
							(mid 0.321484 -0.511984)
							(end 0.381 -0.3683)
						)
						(arc
							(start 0.381 0.3683)
							(mid 0.321484 0.511984)
							(end 0.1778 0.5715)
						)
					)
					(width 0)
					(fill yes)
				)
			)
		)
	)
	(footprint ""
		(layer "F.Cu")
		(at 91.313 -313.817 180)
		(property "Reference" "R9104"
			(at 0 0 180)
			(layer "F.SilkS")
			(hide yes)
			(effects
				(font
					(size 1.27 1.27)
				)
			)
		)
		(property "Value" "27R2F-GP"
			(at 0.064008 -3.993896 180)
			(unlocked yes)
			(layer "F.Fab")
			(hide yes)
			(effects
				(font
					(size 1.016 1.016)
					(thickness 0.1524)
				)
			)
		)
		(property "Device Type" "R402H16"
			(at 0.064008 -5.517896 180)
			(unlocked yes)
			(layer "F.Fab")
			(hide yes)
			(effects
				(font
					(size 1.016 1.016)
					(thickness 0.1524)
				)
			)
		)
		(duplicate_pad_numbers_are_jumpers no)
		(fp_line
			(start 0.508 -0.9398)
			(end -0.508 -0.9398)
			(stroke
				(width 0.1524)
				(type default)
			)
			(layer "F.SilkS")
		)
		(fp_line
			(start -0.508 -0.9398)
			(end -0.508 0.9398)
			(stroke
				(width 0.1524)
				(type default)
			)
			(layer "F.SilkS")
		)
		(fp_rect
			(start -0.508 0.9398)
			(end 0.508 -0.9398)
			(stroke
				(width 0)
				(type default)
			)
			(fill no)
			(layer "F.CrtYd")
		)
		(fp_rect
			(start -0.508 0.9398)
			(end 0.508 -0.9398)
			(stroke
				(width 0)
				(type default)
			)
			(fill no)
			(layer "F.Fab")
		)
		(pad "1" smd custom
			(at 0 -0.4445 180)
			(size 0.1397 0.1397)
			(layers "F.Cu" "F.Mask" "F.Paste")
			(net "PE_CLK_100M_DR11_2_R_P")
			(options
				(clearance outline)
				(anchor circle)
			)
			(primitives
				(gr_poly
					(pts
						(arc
							(start -0.1778 -0.2794)
							(mid -0.249642 -0.249642)
							(end -0.2794 -0.1778)
						)
						(arc
							(start -0.2794 0.1778)
							(mid -0.249642 0.249642)
							(end -0.1778 0.2794)
						)
						(arc
							(start 0.1778 0.2794)
							(mid 0.249642 0.249642)
							(end 0.2794 0.1778)
						)
						(arc
							(start 0.2794 -0.1778)
							(mid 0.249642 -0.249642)
							(end 0.1778 -0.2794)
						)
					)
					(width 0)
					(fill yes)
				)
			)
		)
		(pad "2" smd custom
			(at 0 0.4445 180)
			(size 0.1397 0.1397)
			(layers "F.Cu" "F.Mask" "F.Paste")
			(net "PE_CLK100M_DR11_2_P")
			(options
				(clearance outline)
				(anchor circle)
			)
			(primitives
				(gr_poly
					(pts
						(arc
							(start -0.1778 -0.2794)
							(mid -0.249642 -0.249642)
							(end -0.2794 -0.1778)
						)
						(arc
							(start -0.2794 0.1778)
							(mid -0.249642 0.249642)
							(end -0.1778 0.2794)
						)
						(arc
							(start 0.1778 0.2794)
							(mid 0.249642 0.249642)
							(end 0.2794 0.1778)
						)
						(arc
							(start 0.2794 -0.1778)
							(mid 0.249642 -0.249642)
							(end 0.1778 -0.2794)
						)
					)
					(width 0)
					(fill yes)
				)
			)
		)
	)
)
